# S9S_MB_2U (Grand Teton) — schematic netlist excerpt (pin names and nets, part order shuffled) for the footprints in the layout excerpt that follows; sources: Cadence DE-HDL packaged netlist, KiCad conversion of 03242023_DA0F0TMBIJ0_F0T_Motherboard_J_brd_V01_OCP.brd

R1659  Q_RES  10K 1% CHIP  pkg 0402LF  page 183 : A = FM_PMBUS_ALERT_B_EN ; B = P3V3_AUX
R290  Q_RES  240 1% CHIP  pkg 0402LF  page 119 : A = GND ; B = PD_CPU1_DMIMODE_OVERRIDE

(kicad_pcb
	(version 20260206)
	(generator "pcbnew")
	(generator_version "10.0")
	(general
		(thickness 1.6)
		(legacy_teardrops no)
	)
	(paper "A4")
	(title_block
		(title "03242023_DA0F0TMBIJ0_F0T_Motherboard_J_brd_V01_OCP.brd")
		(comment 1 "Grand Teton / footprints 5321-5322 of 6105")
	)
	(layers
		(0 "F.Cu" signal "TOP")
		(4 "In1.Cu" signal "GND")
		(6 "In2.Cu" signal "IN1")
		(8 "In3.Cu" signal "GND1")
		(10 "In4.Cu" signal "IN2")
		(12 "In5.Cu" signal "GND2")
		(14 "In6.Cu" signal "IN3")
		(16 "In7.Cu" signal "GND3")
		(18 "In8.Cu" signal "VCC")
		(20 "In9.Cu" signal "VCC1")
		(22 "In10.Cu" signal "GND4")
		(24 "In11.Cu" signal "IN4")
		(26 "In12.Cu" signal "GND5")
		(28 "In13.Cu" signal "IN5")
		(30 "In14.Cu" signal "GND6")
		(32 "In15.Cu" signal "IN6")
		(34 "In16.Cu" signal "GND7")
		(2 "B.Cu" signal "BOTTOM")
		(9 "F.Adhes" user "F.Adhesive")
		(11 "B.Adhes" user "B.Adhesive")
		(13 "F.Paste" user "Package Geometry/Pastemask Top")
		(15 "B.Paste" user "Package Geometry/Pastemask Bottom")
		(5 "F.SilkS" user "Ref Des/Silkscreen Top")
		(7 "B.SilkS" user "Ref Des/Silkscreen Bottom")
		(1 "F.Mask" user "Board Geometry/Soldermask Top")
		(3 "B.Mask" user "Board Geometry/Soldermask Bottom")
		(17 "Dwgs.User" user "User.Drawings")
		(19 "Cmts.User" user "User.Comments")
		(21 "Eco1.User" user "User.Eco1")
		(23 "Eco2.User" user "User.Eco2")
		(25 "Edge.Cuts" user "Board Geometry/Outline")
		(27 "Margin" user)
		(31 "F.CrtYd" user "Package Geometry/Place Bound Top")
		(29 "B.CrtYd" user "Package Geometry/Place Bound Bottom")
		(35 "F.Fab" user "Ref Des/Assembly Top")
		(33 "B.Fab" user "Ref Des/Assembly Bottom")
	)
	(footprint ""
		(layer "B.Cu")
		(at 68.29298 -189.374272 -90)
		(property "Reference" "R290"
			(at 0 0 90)
			(layer "B.SilkS")
			(hide yes)
			(effects
				(font
					(size 1.27 1.27)
				)
				(justify mirror)
			)
		)
		(property "Value" ""
			(at 0 0 90)
			(layer "B.Fab")
			(effects
				(font
					(size 1.27 1.27)
				)
				(justify mirror)
			)
		)
		(duplicate_pad_numbers_are_jumpers no)
		(fp_line
			(start -0.7874 0.4064)
			(end 0.7874 0.4064)
			(stroke
				(width 0.1524)
				(type default)
			)
			(layer "B.SilkS")
		)
		(fp_line
			(start 0.7874 0.4064)
			(end 0.7874 -0.4064)
			(stroke
				(width 0.1524)
				(type default)
			)
			(layer "B.SilkS")
		)
		(fp_line
			(start -0.7874 -0.4064)
			(end -0.7874 0.4064)
			(stroke
				(width 0.1524)
				(type default)
			)
			(layer "B.SilkS")
		)
		(fp_line
			(start 0.7874 -0.4064)
			(end -0.7874 -0.4064)
			(stroke
				(width 0.1524)
				(type default)
			)
			(layer "B.SilkS")
		)
		(fp_line
			(start -0.67945 0.3048)
			(end -0.120396 0.3048)
			(stroke
				(width 0.1)
				(type default)
			)
			(layer "B.Fab")
		)
		(fp_line
			(start -0.120396 0.3048)
			(end -0.120396 0.2794)
			(stroke
				(width 0.1)
				(type default)
			)
			(layer "B.Fab")
		)
		(fp_line
			(start 0.12065 0.3048)
			(end 0.67945 0.3048)
			(stroke
				(width 0.1)
				(type default)
			)
			(layer "B.Fab")
		)
		(fp_line
			(start 0.67945 0.3048)
			(end 0.67945 -0.305054)
			(stroke
				(width 0.1)
				(type default)
			)
			(layer "B.Fab")
		)
		(fp_line
			(start -0.120396 0.2794)
			(end 0.12065 0.2794)
			(stroke
				(width 0.1)
				(type default)
			)
			(layer "B.Fab")
		)
		(fp_line
			(start 0.12065 0.2794)
			(end 0.12065 0.3048)
			(stroke
				(width 0.1)
				(type default)
			)
			(layer "B.Fab")
		)
		(fp_line
			(start -0.12065 -0.2794)
			(end -0.12065 -0.3048)
			(stroke
				(width 0.1)
				(type default)
			)
			(layer "B.Fab")
		)
		(fp_line
			(start 0.12065 -0.2794)
			(end -0.12065 -0.2794)
			(stroke
				(width 0.1)
				(type default)
			)
			(layer "B.Fab")
		)
		(fp_line
			(start -0.67945 -0.3048)
			(end -0.67945 0.3048)
			(stroke
				(width 0.1)
				(type default)
			)
			(layer "B.Fab")
		)
		(fp_line
			(start -0.12065 -0.3048)
			(end -0.67945 -0.3048)
			(stroke
				(width 0.1)
				(type default)
			)
			(layer "B.Fab")
		)
		(fp_line
			(start 0.12065 -0.305054)
			(end 0.12065 -0.2794)
			(stroke
				(width 0.1)
				(type default)
			)
			(layer "B.Fab")
		)
		(fp_line
			(start 0.67945 -0.305054)
			(end 0.12065 -0.305054)
			(stroke
				(width 0.1)
				(type default)
			)
			(layer "B.Fab")
		)
		(pad "1" smd circle
			(at 0.40005 0 90)
			(size 0 0)
			(layers "B.Cu" "B.Mask" "B.Paste")
			(net "GND")
		)
		(pad "2" smd circle
			(at -0.40005 0 90)
			(size 0 0)
			(layers "B.Cu" "B.Mask" "B.Paste")
			(net "PD_CPU1_DMIMODE_OVERRIDE")
		)
	)
	(footprint ""
		(layer "B.Cu")
		(at 321.369182 -39.574724 45)
		(property "Reference" "R1659"
			(at 0 0 45)
			(layer "B.SilkS")
			(hide yes)
			(effects
				(font
					(size 1.27 1.27)
				)
				(justify mirror)
			)
		)
		(property "Value" ""
			(at 0 0 45)
			(layer "B.Fab")
			(effects
				(font
					(size 1.27 1.27)
				)
				(justify mirror)
			)
		)
		(duplicate_pad_numbers_are_jumpers no)
		(fp_line
			(start -0.787389 -0.406267)
			(end -0.787389 0.406267)
			(stroke
				(width 0.1524)
				(type default)
			)
			(layer "B.SilkS")
		)
		(fp_line
			(start -0.787389 0.406267)
			(end 0.787389 0.406267)
			(stroke
				(width 0.1524)
				(type default)
			)
			(layer "B.SilkS")
		)
		(fp_line
			(start 0.787389 -0.406267)
			(end -0.787389 -0.406267)
			(stroke
				(width 0.1524)
				(type default)
			)
			(layer "B.SilkS")
		)
		(fp_line
			(start 0.787389 0.406267)
			(end 0.787389 -0.406267)
			(stroke
				(width 0.1524)
				(type default)
			)
			(layer "B.SilkS")
		)
		(fp_line
			(start -0.679446 -0.30479)
			(end -0.679446 0.30479)
			(stroke
				(width 0.1)
				(type default)
			)
			(layer "B.Fab")
		)
		(fp_line
			(start -0.120515 -0.30479)
			(end -0.679446 -0.30479)
			(stroke
				(width 0.1)
				(type default)
			)
			(layer "B.Fab")
		)
		(fp_line
			(start -0.120695 -0.279466)
			(end -0.120515 -0.30479)
			(stroke
				(width 0.1)
				(type default)
			)
			(layer "B.Fab")
		)
		(fp_line
			(start -0.679446 0.30479)
			(end -0.120515 0.30479)
			(stroke
				(width 0.1)
				(type default)
			)
			(layer "B.Fab")
		)
		(fp_line
			(start 0.120695 -0.304969)
			(end 0.120695 -0.279466)
			(stroke
				(width 0.1)
				(type default)
			)
			(layer "B.Fab")
		)
		(fp_line
			(start 0.120695 -0.279466)
			(end -0.120695 -0.279466)
			(stroke
				(width 0.1)
				(type default)
			)
			(layer "B.Fab")
		)
		(fp_line
			(start -0.120335 0.279466)
			(end 0.120695 0.279466)
			(stroke
				(width 0.1)
				(type default)
			)
			(layer "B.Fab")
		)
		(fp_line
			(start -0.120515 0.30479)
			(end -0.120335 0.279466)
			(stroke
				(width 0.1)
				(type default)
			)
			(layer "B.Fab")
		)
		(fp_line
			(start 0.679446 -0.305149)
			(end 0.120695 -0.304969)
			(stroke
				(width 0.1)
				(type default)
			)
			(layer "B.Fab")
		)
		(fp_line
			(start 0.120695 0.279466)
			(end 0.120515 0.30479)
			(stroke
				(width 0.1)
				(type default)
			)
			(layer "B.Fab")
		)
		(fp_line
			(start 0.120515 0.30479)
			(end 0.679446 0.30479)
			(stroke
				(width 0.1)
				(type default)
			)
			(layer "B.Fab")
		)
		(fp_line
			(start 0.679446 0.30479)
			(end 0.679446 -0.305149)
			(stroke
				(width 0.1)
				(type default)
			)
			(layer "B.Fab")
		)
		(pad "1" smd circle
			(at 0.40005 0 225)
			(size 0 0)
			(layers "B.Cu" "B.Mask" "B.Paste")
			(net "FM_PMBUS_ALERT_B_EN")
		)
		(pad "2" smd circle
			(at -0.40005 0 225)
			(size 0 0)
			(layers "B.Cu" "B.Mask" "B.Paste")
			(net "P3V3_AUX")
		)
	)
)
